(kicad_pcb
	(version 20260206)
	(generator "pcbnew")
	(generator_version "10.0")
	(general
		(thickness 1.6)
		(legacy_teardrops no)
	)
	(paper "A4")
	(title_block
		(title "Bryce Canyon_F.DPB_16315-1-OCP.brd")
		(comment 1 "Bryce Canyon / footprints 937-938 of 2223")
	)
	(layers
		(0 "F.Cu" signal "TOP")
		(4 "In1.Cu" signal "L2GND")
		(6 "In2.Cu" signal "L3")
		(8 "In3.Cu" signal "L4GND")
		(10 "In4.Cu" signal "L5")
		(12 "In5.Cu" signal "L6VCC")
		(14 "In6.Cu" signal "L7VCC")
		(16 "In7.Cu" signal "L8")
		(18 "In8.Cu" signal "L9GND")
		(20 "In9.Cu" signal "L10")
		(22 "In10.Cu" signal "L11GND")
		(2 "B.Cu" signal "BOTTOM")
		(9 "F.Adhes" user "F.Adhesive")
		(11 "B.Adhes" user "B.Adhesive")
		(13 "F.Paste" user "Package Geometry/Pastemask Top")
		(15 "B.Paste" user "Package Geometry/Pastemask Bottom")
		(5 "F.SilkS" user "Ref Des/Silkscreen Top")
		(7 "B.SilkS" user "Ref Des/Silkscreen Bottom")
		(1 "F.Mask" user "Board Geometry/Soldermask Top")
		(3 "B.Mask" user "Board Geometry/Soldermask Bottom")
		(17 "Dwgs.User" user "User.Drawings")
		(19 "Cmts.User" user "User.Comments")
		(21 "Eco1.User" user "User.Eco1")
		(23 "Eco2.User" user "User.Eco2")
		(25 "Edge.Cuts" user "Board Geometry/Outline")
		(27 "Margin" user)
		(31 "F.CrtYd" user "Package Geometry/Place Bound Top")
		(29 "B.CrtYd" user "Package Geometry/Place Bound Bottom")
		(35 "F.Fab" user "Ref Des/Assembly Top")
		(33 "B.Fab" user "Ref Des/Assembly Bottom")
	)
	(footprint ""
		(layer "F.Cu")
		(at 381.36195 -176.127918 -90)
		(property "Reference" "C303"
			(at 0 0 270)
			(layer "F.SilkS")
			(hide yes)
			(effects
				(font
					(size 1.27 1.27)
				)
			)
		)
		(property "Value" "SCD01U50V2KX-1GP"
			(at 1.1811 -2.7051 270)
			(unlocked yes)
			(layer "F.Fab")
			(hide yes)
			(effects
				(font
					(size 1.016 1.016)
					(thickness 0.1524)
				)
			)
		)
		(property "Device Type" "C402H22"
			(at 1.1811 -4.2291 270)
			(unlocked yes)
			(layer "F.Fab")
			(hide yes)
			(effects
				(font
					(size 1.016 1.016)
					(thickness 0.1524)
				)
			)
		)
		(duplicate_pad_numbers_are_jumpers no)
		(fp_rect
			(start -0.4318 0.9525)
			(end 0.4318 -0.9525)
			(stroke
				(width 0)
				(type default)
			)
			(fill no)
			(layer "F.CrtYd")
		)
		(fp_rect
			(start -0.4318 0.9525)
			(end 0.4318 -0.9525)
			(stroke
				(width 0)
				(type default)
			)
			(fill no)
			(layer "F.Fab")
		)
		(pad "1" smd custom
			(at 0 -0.4445 270)
			(size 0.1524 0.1524)
			(layers "F.Cu" "F.Mask" "F.Paste")
			(net "HDD_PRSNT_20")
			(options
				(clearance outline)
				(anchor circle)
			)
			(primitives
				(gr_poly
					(pts
						(arc
							(start 0.3048 -0.2032)
							(mid 0.275042 -0.275042)
							(end 0.2032 -0.3048)
						)
						(arc
							(start -0.2032 -0.3048)
							(mid -0.275042 -0.275042)
							(end -0.3048 -0.2032)
						)
						(arc
							(start -0.3048 0.2032)
							(mid -0.275042 0.275042)
							(end -0.2032 0.3048)
						)
						(arc
							(start 0.2032 0.3048)
							(mid 0.275042 0.275042)
							(end 0.3048 0.2032)
						)
					)
					(width 0)
					(fill yes)
				)
			)
		)
		(pad "2" smd custom
			(at 0 0.4445 270)
			(size 0.1524 0.1524)
			(layers "F.Cu" "F.Mask" "F.Paste")
			(net "GND")
			(options
				(clearance outline)
				(anchor circle)
			)
			(primitives
				(gr_poly
					(pts
						(arc
							(start 0.3048 -0.2032)
							(mid 0.275042 -0.275042)
							(end 0.2032 -0.3048)
						)
						(arc
							(start -0.2032 -0.3048)
							(mid -0.275042 -0.275042)
							(end -0.3048 -0.2032)
						)
						(arc
							(start -0.3048 0.2032)
							(mid -0.275042 0.275042)
							(end -0.2032 0.3048)
						)
						(arc
							(start 0.2032 0.3048)
							(mid 0.275042 0.275042)
							(end 0.3048 0.2032)
						)
					)
					(width 0)
					(fill yes)
				)
			)
		)
	)
	(footprint ""
		(layer "F.Cu")
		(at 86.096348 -46.014894 -90)
		(property "Reference" "R736"
			(at 0 0 270)
			(layer "F.SilkS")
			(hide yes)
			(effects
				(font
					(size 1.27 1.27)
				)
			)
		)
		(property "Value" "1KR2F-3-GP"
			(at 0.064008 -3.993896 270)
			(unlocked yes)
			(layer "F.Fab")
			(hide yes)
			(effects
				(font
					(size 1.016 1.016)
					(thickness 0.1524)
				)
			)
		)
		(property "Device Type" "R402H16"
			(at 0.064008 -5.517896 270)
			(unlocked yes)
			(layer "F.Fab")
			(hide yes)
			(effects
				(font
					(size 1.016 1.016)
					(thickness 0.1524)
				)
			)
		)
		(duplicate_pad_numbers_are_jumpers no)
		(fp_line
			(start -0.508 -0.9398)
			(end -0.508 0.9398)
			(stroke
				(width 0.1524)
				(type default)
			)
			(layer "F.SilkS")
		)
		(fp_line
			(start 0.508 -0.9398)
			(end -0.508 -0.9398)
			(stroke
				(width 0.1524)
				(type default)
			)
			(layer "F.SilkS")
		)
		(fp_rect
			(start -0.508 0.9398)
			(end 0.508 -0.9398)
			(stroke
				(width 0)
				(type default)
			)
			(fill no)
			(layer "F.CrtYd")
		)
		(fp_rect
			(start -0.508 0.9398)
			(end 0.508 -0.9398)
			(stroke
				(width 0)
				(type default)
			)
			(fill no)
			(layer "F.Fab")
		)
		(pad "1" smd custom
			(at 0 -0.4445 270)
			(size 0.1397 0.1397)
			(layers "F.Cu" "F.Mask" "F.Paste")
			(net "P3V3_STBY_A")
			(options
				(clearance outline)
				(anchor circle)
			)
			(primitives
				(gr_poly
					(pts
						(arc
							(start -0.1778 -0.2794)
							(mid -0.249642 -0.249642)
							(end -0.2794 -0.1778)
						)
						(arc
							(start -0.2794 0.1778)
							(mid -0.249642 0.249642)
							(end -0.1778 0.2794)
						)
						(arc
							(start 0.1778 0.2794)
							(mid 0.249642 0.249642)
							(end 0.2794 0.1778)
						)
						(arc
							(start 0.2794 -0.1778)
							(mid 0.249642 -0.249642)
							(end 0.1778 -0.2794)
						)
					)
					(width 0)
					(fill yes)
				)
			)
		)
		(pad "2" smd custom
			(at 0 0.4445 270)
			(size 0.1397 0.1397)
			(layers "F.Cu" "F.Mask" "F.Paste")
			(net "SW_PWR_R_HDD26")
			(options
				(clearance outline)
				(anchor circle)
			)
			(primitives
				(gr_poly
					(pts
						(arc
							(start -0.1778 -0.2794)
							(mid -0.249642 -0.249642)
							(end -0.2794 -0.1778)
						)
						(arc
							(start -0.2794 0.1778)
							(mid -0.249642 0.249642)
							(end -0.1778 0.2794)
						)
						(arc
							(start 0.1778 0.2794)
							(mid 0.249642 0.249642)
							(end 0.2794 0.1778)
						)
						(arc
							(start 0.2794 -0.1778)
							(mid 0.249642 -0.249642)
							(end 0.1778 -0.2794)
						)
					)
					(width 0)
					(fill yes)
				)
			)
		)
	)
)
